# BASEBOARD_FAB2 (Tioga Pass) — schematic netlist excerpt (pin names and nets, part order shuffled) for the footprints in the layout excerpt that follows; sources: Cadence DE-HDL packaged netlist, KiCad conversion of Wiwynn_Tioga_Pass_MB.brd

C8G10  CAP  0.22UF 16V 10% X7R  pkg 0402  page 105 : A = P3E_CPU0_PE2_SS_TXN<0> ; B = P3E_CPU0_PE2_SS_C_TXN<0>
R2P14  RES  0.0 5% CHIP  pkg 0402  page 185 : A = FM_M2_DET_LVC3 ; B = FM_SSATA_PCIE_M2_SEL
C5A5  CAP_A  47UF 4V 20% X5R  pkg 0603V  page 220 : A = PVDDQ_DEF ; B = GND

(kicad_pcb
	(version 20260206)
	(generator "pcbnew")
	(generator_version "10.0")
	(general
		(thickness 1.6)
		(legacy_teardrops no)
	)
	(paper "A4")
	(title_block
		(title "Wiwynn_Tioga_Pass_MB.brd")
		(comment 1 "Tioga Pass / footprints 816-818 of 4770")
	)
	(layers
		(0 "F.Cu" signal "TOP")
		(4 "In1.Cu" signal "L2GND")
		(6 "In2.Cu" signal "L3")
		(8 "In3.Cu" signal "L4GND")
		(10 "In4.Cu" signal "L5")
		(12 "In5.Cu" signal "L6GND")
		(14 "In6.Cu" signal "L7VCC")
		(16 "In7.Cu" signal "L8VCC")
		(18 "In8.Cu" signal "L9GND")
		(20 "In9.Cu" signal "L10")
		(22 "In10.Cu" signal "L11GND")
		(24 "In11.Cu" signal "L12")
		(26 "In12.Cu" signal "L13GND")
		(2 "B.Cu" signal "BOTTOM")
		(9 "F.Adhes" user "F.Adhesive")
		(11 "B.Adhes" user "B.Adhesive")
		(13 "F.Paste" user "Package Geometry/Pastemask Top")
		(15 "B.Paste" user "Package Geometry/Pastemask Bottom")
		(5 "F.SilkS" user "Ref Des/Silkscreen Top")
		(7 "B.SilkS" user "Ref Des/Silkscreen Bottom")
		(1 "F.Mask" user "Board Geometry/Soldermask Top")
		(3 "B.Mask" user "Board Geometry/Soldermask Bottom")
		(17 "Dwgs.User" user "User.Drawings")
		(19 "Cmts.User" user "User.Comments")
		(21 "Eco1.User" user "User.Eco1")
		(23 "Eco2.User" user "User.Eco2")
		(25 "Edge.Cuts" user "Board Geometry/Outline")
		(27 "Margin" user)
		(31 "F.CrtYd" user "Package Geometry/Place Bound Top")
		(29 "B.CrtYd" user "Package Geometry/Place Bound Bottom")
		(35 "F.Fab" user "Ref Des/Assembly Top")
		(33 "B.Fab" user "Ref Des/Assembly Bottom")
	)
	(footprint ""
		(layer "F.Cu")
		(at 257.8608 -149.733 -90)
		(property "Reference" "C5A5"
			(at 0 0 270)
			(layer "F.SilkS")
			(hide yes)
			(effects
				(font
					(size 1.27 1.27)
				)
			)
		)
		(property "Value" ""
			(at 0 0 270)
			(layer "F.Fab")
			(effects
				(font
					(size 1.27 1.27)
				)
			)
		)
		(duplicate_pad_numbers_are_jumpers no)
		(fp_rect
			(start -0.500126 1.598422)
			(end 0.500126 -0.201422)
			(stroke
				(width 0)
				(type default)
			)
			(fill no)
			(layer "F.CrtYd")
		)
		(fp_line
			(start -0.500126 1.598422)
			(end -0.500126 -0.201422)
			(stroke
				(width 0.1)
				(type default)
			)
			(layer "F.Fab")
		)
		(fp_line
			(start 0.500126 1.598422)
			(end -0.500126 1.598422)
			(stroke
				(width 0.1)
				(type default)
			)
			(layer "F.Fab")
		)
		(fp_line
			(start -0.500126 -0.201422)
			(end 0.500126 -0.201422)
			(stroke
				(width 0.1)
				(type default)
			)
			(layer "F.Fab")
		)
		(fp_line
			(start 0.500126 -0.201422)
			(end 0.500126 1.598422)
			(stroke
				(width 0.1)
				(type default)
			)
			(layer "F.Fab")
		)
		(pad "1" smd rect
			(at 0 0 180)
			(size 0.889 0.9906)
			(layers "F.Cu" "F.Mask" "F.Paste")
			(net "PVDDQ_DEF")
		)
		(pad "2" smd rect
			(at 0 1.397 180)
			(size 0.889 0.9906)
			(layers "F.Cu" "F.Mask" "F.Paste")
			(net "GND")
		)
		(zone
			(layer "F.Cu")
			(hatch none 0.5)
			(connect_pads
				(clearance 0)
			)
			(min_thickness 0.25)
			(keepout
				(tracks allowed)
				(vias not_allowed)
				(pads allowed)
				(copperpour not_allowed)
				(footprints allowed)
			)
			(placement
				(enabled no)
				(sheetname "")
			)
			(fill
				(thermal_gap 0.5)
				(thermal_bridge_width 0.5)
				(island_removal_mode 0)
			)
			(polygon
				(pts
					(xy 256.9083 -150.2283) (xy 256.9083 -149.2377) (xy 257.4163 -149.2377) (xy 257.4163 -150.2283)
				)
			)
		)
		(zone
			(layer "F.Cu")
			(hatch none 0.5)
			(connect_pads
				(clearance 0)
			)
			(min_thickness 0.25)
			(keepout
				(tracks not_allowed)
				(vias allowed)
				(pads allowed)
				(copperpour not_allowed)
				(footprints allowed)
			)
			(placement
				(enabled no)
				(sheetname "")
			)
			(fill
				(thermal_gap 0.5)
				(thermal_bridge_width 0.5)
				(island_removal_mode 0)
			)
			(polygon
				(pts
					(xy 256.9083 -150.2283) (xy 256.9083 -149.2377) (xy 257.4163 -149.2377) (xy 257.4163 -150.2283)
				)
			)
		)
	)
	(footprint ""
		(layer "F.Cu")
		(at 400.685 -84.0105 180)
		(property "Reference" "R2P14"
			(at 0 0 180)
			(layer "F.SilkS")
			(hide yes)
			(effects
				(font
					(size 1.27 1.27)
				)
			)
		)
		(property "Value" ""
			(at 0 0 180)
			(layer "F.Fab")
			(effects
				(font
					(size 1.27 1.27)
				)
			)
		)
		(duplicate_pad_numbers_are_jumpers no)
		(fp_poly
			(pts
				(xy -0.2794 -0.1016) (xy 0.2794 -0.1016) (xy 0.2794 0.9906) (xy -0.2794 0.9906)
			)
			(stroke
				(width 0)
				(type default)
			)
			(fill no)
			(layer "F.CrtYd")
		)
		(fp_line
			(start 0.2794 0.9906)
			(end 0.2794 -0.1016)
			(stroke
				(width 0.1)
				(type default)
			)
			(layer "F.Fab")
		)
		(fp_line
			(start 0.2794 -0.1016)
			(end -0.2794 -0.1016)
			(stroke
				(width 0.1)
				(type default)
			)
			(layer "F.Fab")
		)
		(fp_line
			(start -0.2794 0.9906)
			(end 0.2794 0.9906)
			(stroke
				(width 0.1)
				(type default)
			)
			(layer "F.Fab")
		)
		(fp_line
			(start -0.2794 -0.1016)
			(end -0.2794 0.9906)
			(stroke
				(width 0.1)
				(type default)
			)
			(layer "F.Fab")
		)
		(pad "1" smd rect
			(at 0 0 180)
			(size 0.508 0.508)
			(layers "F.Cu" "F.Mask" "F.Paste")
			(net "FM_M2_DET_LVC3")
		)
		(pad "2" smd rect
			(at 0 0.889 180)
			(size 0.508 0.508)
			(layers "F.Cu" "F.Mask" "F.Paste")
			(net "FM_SSATA_PCIE_M2_SEL")
		)
		(zone
			(layer "F.Cu")
			(hatch none 0.5)
			(connect_pads
				(clearance 0)
			)
			(min_thickness 0.25)
			(keepout
				(tracks not_allowed)
				(vias allowed)
				(pads allowed)
				(copperpour not_allowed)
				(footprints allowed)
			)
			(placement
				(enabled no)
				(sheetname "")
			)
			(fill
				(thermal_gap 0.5)
				(thermal_bridge_width 0.5)
				(island_removal_mode 0)
			)
			(polygon
				(pts
					(xy 400.939 -84.6455) (xy 400.431 -84.6455) (xy 400.431 -84.2645) (xy 400.939 -84.2645)
				)
			)
		)
		(zone
			(layer "F.Cu")
			(hatch none 0.5)
			(connect_pads
				(clearance 0)
			)
			(min_thickness 0.25)
			(keepout
				(tracks allowed)
				(vias not_allowed)
				(pads allowed)
				(copperpour not_allowed)
				(footprints allowed)
			)
			(placement
				(enabled no)
				(sheetname "")
			)
			(fill
				(thermal_gap 0.5)
				(thermal_bridge_width 0.5)
				(island_removal_mode 0)
			)
			(polygon
				(pts
					(xy 400.939 -84.2645) (xy 400.431 -84.2645) (xy 400.431 -84.6455) (xy 400.939 -84.6455)
				)
			)
		)
	)
	(footprint ""
		(layer "F.Cu")
		(at 410.817822 -11.436858)
		(property "Reference" "C8G10"
			(at 0 0 0)
			(layer "F.SilkS")
			(hide yes)
			(effects
				(font
					(size 1.27 1.27)
				)
			)
		)
		(property "Value" ""
			(at 0 0 0)
			(layer "F.Fab")
			(effects
				(font
					(size 1.27 1.27)
				)
			)
		)
		(duplicate_pad_numbers_are_jumpers no)
		(fp_rect
			(start -0.3048 0.9906)
			(end 0.3048 -0.1016)
			(stroke
				(width 0)
				(type default)
			)
			(fill no)
			(layer "F.CrtYd")
		)
		(fp_line
			(start -0.3048 -0.1016)
			(end -0.3048 0.9906)
			(stroke
				(width 0.1)
				(type default)
			)
			(layer "F.Fab")
		)
		(fp_line
			(start -0.3048 0.9906)
			(end 0.3048 0.9906)
			(stroke
				(width 0.1)
				(type default)
			)
			(layer "F.Fab")
		)
		(fp_line
			(start 0.3048 -0.1016)
			(end -0.3048 -0.1016)
			(stroke
				(width 0.1)
				(type default)
			)
			(layer "F.Fab")
		)
		(fp_line
			(start 0.3048 0.9906)
			(end 0.3048 -0.1016)
			(stroke
				(width 0.1)
				(type default)
			)
			(layer "F.Fab")
		)
		(pad "1" smd rect
			(at 0 0)
			(size 0.508 0.508)
			(layers "F.Cu" "F.Mask" "F.Paste")
			(net "P3E_CPU0_PE2_SS_TXN<0>")
		)
		(pad "2" smd rect
			(at 0 0.889)
			(size 0.508 0.508)
			(layers "F.Cu" "F.Mask" "F.Paste")
			(net "P3E_CPU0_PE2_SS_C_TXN<0>")
		)
		(zone
			(layer "F.Cu")
			(hatch none 0.5)
			(connect_pads
				(clearance 0)
			)
			(min_thickness 0.25)
			(keepout
				(tracks allowed)
				(vias not_allowed)
				(pads allowed)
				(copperpour not_allowed)
				(footprints allowed)
			)
			(placement
				(enabled no)
				(sheetname "")
			)
			(fill
				(thermal_gap 0.5)
				(thermal_bridge_width 0.5)
				(island_removal_mode 0)
			)
			(polygon
				(pts
					(xy 410.563822 -10.801858) (xy 411.071822 -10.801858) (xy 411.071822 -11.182858) (xy 410.563822 -11.182858)
				)
			)
		)
		(zone
			(layer "F.Cu")
			(hatch none 0.5)
			(connect_pads
				(clearance 0)
			)
			(min_thickness 0.25)
			(keepout
				(tracks not_allowed)
				(vias allowed)
				(pads allowed)
				(copperpour not_allowed)
				(footprints allowed)
			)
			(placement
				(enabled no)
				(sheetname "")
			)
			(fill
				(thermal_gap 0.5)
				(thermal_bridge_width 0.5)
				(island_removal_mode 0)
			)
			(polygon
				(pts
					(xy 410.563822 -10.801858) (xy 411.071822 -10.801858) (xy 411.071822 -11.182858) (xy 410.563822 -11.182858)
				)
			)
		)
	)
)
